(kicad_pcb
	(version 20260206)
	(generator "pcbnew")
	(generator_version "10.0")
	(general
		(thickness 1.6)
		(legacy_teardrops no)
	)
	(paper "A4")
	(title_block
		(title "03242023_DA0F0TMBIJ0_F0T_Motherboard_J_brd_V01_OCP.brd")
		(comment 1 "Grand Teton / footprint 1682 of 6105 (U1), pads 2145-2254 of 4677")
	)
	(layers
		(0 "F.Cu" signal "TOP")
		(4 "In1.Cu" signal "GND")
		(6 "In2.Cu" signal "IN1")
		(8 "In3.Cu" signal "GND1")
		(10 "In4.Cu" signal "IN2")
		(12 "In5.Cu" signal "GND2")
		(14 "In6.Cu" signal "IN3")
		(16 "In7.Cu" signal "GND3")
		(18 "In8.Cu" signal "VCC")
		(20 "In9.Cu" signal "VCC1")
		(22 "In10.Cu" signal "GND4")
		(24 "In11.Cu" signal "IN4")
		(26 "In12.Cu" signal "GND5")
		(28 "In13.Cu" signal "IN5")
		(30 "In14.Cu" signal "GND6")
		(32 "In15.Cu" signal "IN6")
		(34 "In16.Cu" signal "GND7")
		(2 "B.Cu" signal "BOTTOM")
		(9 "F.Adhes" user "F.Adhesive")
		(11 "B.Adhes" user "B.Adhesive")
		(13 "F.Paste" user "Package Geometry/Pastemask Top")
		(15 "B.Paste" user "Package Geometry/Pastemask Bottom")
		(5 "F.SilkS" user "Ref Des/Silkscreen Top")
		(7 "B.SilkS" user "Ref Des/Silkscreen Bottom")
		(1 "F.Mask" user "Board Geometry/Soldermask Top")
		(3 "B.Mask" user "Board Geometry/Soldermask Bottom")
		(17 "Dwgs.User" user "User.Drawings")
		(19 "Cmts.User" user "User.Comments")
		(21 "Eco1.User" user "User.Eco1")
		(23 "Eco2.User" user "User.Eco2")
		(25 "Edge.Cuts" user "Board Geometry/Outline")
		(27 "Margin" user)
		(31 "F.CrtYd" user "Package Geometry/Place Bound Top")
		(29 "B.CrtYd" user "Package Geometry/Place Bound Bottom")
		(35 "F.Fab" user "Ref Des/Assembly Top")
		(33 "B.Fab" user "Ref Des/Assembly Bottom")
	)
	(footprint ""
		(layer "F.Cu")
		(at 111.93018 -251.76988 90)
		(property "Reference" "U1"
			(at -74.913236 41.548812 0)
			(unlocked yes)
			(layer "F.SilkS")
			(effects
				(font
					(size 1.6002 1.1938)
					(thickness 0.1524)
				)
				(justify left)
			)
		)
		(property "Value" ""
			(at 0 0 90)
			(layer "F.Fab")
			(effects
				(font
					(size 1.27 1.27)
				)
			)
		)
		(duplicate_pad_numbers_are_jumpers no)
		(pad "CR5" smd circle
			(at -34.169604 7.698486 270)
			(size 0.4318 0.4318)
			(layers "F.Cu" "F.Mask" "F.Paste")
			(net "GND")
		)
		(pad "CR7" smd circle
			(at -32.541718 7.698486 270)
			(size 0.4318 0.4318)
			(layers "F.Cu" "F.Mask" "F.Paste")
			(net "UPI_CPU1_CPU0_P1P0_DP<15>")
		)
		(pad "CR9" smd circle
			(at -30.914086 7.698486 270)
			(size 0.4318 0.4318)
			(layers "F.Cu" "F.Mask" "F.Paste")
			(net "GND")
		)
		(pad "CR11" smd circle
			(at -29.2862 7.698486 270)
			(size 0.4318 0.4318)
			(layers "F.Cu" "F.Mask" "F.Paste")
			(net "GND")
		)
		(pad "CR13" smd circle
			(at -27.658314 7.698486 270)
			(size 0.4318 0.4318)
			(layers "F.Cu" "F.Mask" "F.Paste")
			(net "GND")
		)
		(pad "CR15" smd circle
			(at -26.030682 7.698486 270)
			(size 0.4318 0.4318)
			(layers "F.Cu" "F.Mask" "F.Paste")
			(net "P5E_CPU1_PE1_TX_DP<0>")
		)
		(pad "CR17" smd circle
			(at -24.402796 7.698486 270)
			(size 0.4318 0.4318)
			(layers "F.Cu" "F.Mask" "F.Paste")
			(net "GND")
		)
		(pad "CR19" smd circle
			(at -22.77491 7.698486 270)
			(size 0.4318 0.4318)
			(layers "F.Cu" "F.Mask" "F.Paste")
			(net "TP_H_SBLINK5_CPU1_PMSYNC")
		)
		(pad "CR21" smd circle
			(at -21.147278 7.698486 270)
			(size 0.4318 0.4318)
			(layers "F.Cu" "F.Mask" "F.Paste")
			(net "TP_FM_IBL_SLPS3_CPU1_R_N")
		)
		(pad "CR23" smd circle
			(at -19.519392 7.698486 270)
			(size 0.4318 0.4318)
			(layers "F.Cu" "F.Mask" "F.Paste")
			(net "CPU1_RSVD<126>")
		)
		(pad "CR25" smd circle
			(at -17.89176 7.698486 270)
			(size 0.4318 0.4318)
			(layers "F.Cu" "F.Mask" "F.Paste")
			(net "NC_CPU1_VIEWPIN_GNR2")
		)
		(pad "CR60" smd circle
			(at 12.19454 7.808468 270)
			(size 0.4318 0.4318)
			(layers "F.Cu" "F.Mask" "F.Paste")
			(net "NC_CPU1_LGSSPARE0")
		)
		(pad "CR62" smd circle
			(at 13.822426 7.808468 270)
			(size 0.4318 0.4318)
			(layers "F.Cu" "F.Mask" "F.Paste")
			(net "GND")
		)
		(pad "CR64" smd circle
			(at 15.450058 7.808468 270)
			(size 0.4318 0.4318)
			(layers "F.Cu" "F.Mask" "F.Paste")
			(net "GND")
		)
		(pad "CR66" smd circle
			(at 17.07769 7.808468 270)
			(size 0.4318 0.4318)
			(layers "F.Cu" "F.Mask" "F.Paste")
			(net "PVCCINFAON_CPU1")
		)
		(pad "CR68" smd circle
			(at 18.705576 7.808468 270)
			(size 0.4318 0.4318)
			(layers "F.Cu" "F.Mask" "F.Paste")
			(net "NC_CPU1_UPI3_APROBE<1>")
		)
		(pad "CR70" smd circle
			(at 20.333462 7.808468 270)
			(size 0.4318 0.4318)
			(layers "F.Cu" "F.Mask" "F.Paste")
			(net "PU_PIROM_CPU1_ADDR0")
		)
		(pad "CR72" smd circle
			(at 21.961094 7.808468 270)
			(size 0.4318 0.4318)
			(layers "F.Cu" "F.Mask" "F.Paste")
			(net "PU_PIROM_CPU1_SM_WP")
		)
		(pad "CR74" smd circle
			(at 23.58898 7.808468 270)
			(size 0.4318 0.4318)
			(layers "F.Cu" "F.Mask" "F.Paste")
			(net "Net_742")
		)
		(pad "CR76" smd circle
			(at 25.216612 7.808468 270)
			(size 0.4318 0.4318)
			(layers "F.Cu" "F.Mask" "F.Paste")
			(net "Net_719")
		)
		(pad "CR78" smd circle
			(at 26.844498 7.808468 270)
			(size 0.4318 0.4318)
			(layers "F.Cu" "F.Mask" "F.Paste")
			(net "GND")
		)
		(pad "CR80" smd circle
			(at 28.472384 7.808468 270)
			(size 0.4318 0.4318)
			(layers "F.Cu" "F.Mask" "F.Paste")
			(net "GND")
		)
		(pad "CR82" smd circle
			(at 30.100016 7.808468 270)
			(size 0.4318 0.4318)
			(layers "F.Cu" "F.Mask" "F.Paste")
			(net "GND")
		)
		(pad "CR84" smd circle
			(at 31.727902 7.808468 270)
			(size 0.4318 0.4318)
			(layers "F.Cu" "F.Mask" "F.Paste")
			(net "GND")
		)
		(pad "CR86" smd circle
			(at 33.355534 7.808468 270)
			(size 0.4318 0.4318)
			(layers "F.Cu" "F.Mask" "F.Paste")
			(net "P5E_CPU1_PE3_TX_DP<15>")
		)
		(pad "CR88" smd circle
			(at 34.98342 7.808468 270)
			(size 0.4318 0.4318)
			(layers "F.Cu" "F.Mask" "F.Paste")
			(net "GND")
		)
		(pad "CR90" smd circle
			(at 36.611306 7.808468 270)
			(size 0.4318 0.4318)
			(layers "F.Cu" "F.Mask" "F.Paste")
			(net "GND")
		)
		(pad "CT2" smd circle
			(at -36.611306 8.168132 270)
			(size 0.4318 0.4318)
			(layers "F.Cu" "F.Mask" "F.Paste")
			(net "UPI_CPU0_CPU1_P0P1_DP<16>")
		)
		(pad "CT4" smd circle
			(at -34.98342 8.168132 270)
			(size 0.4318 0.4318)
			(layers "F.Cu" "F.Mask" "F.Paste")
			(net "GND")
		)
		(pad "CT6" smd circle
			(at -33.355534 8.168132 270)
			(size 0.4318 0.4318)
			(layers "F.Cu" "F.Mask" "F.Paste")
			(net "UPI_CPU1_CPU0_P1P0_DN<15>")
		)
		(pad "CT8" smd circle
			(at -31.727902 8.168132 270)
			(size 0.4318 0.4318)
			(layers "F.Cu" "F.Mask" "F.Paste")
			(net "GND")
		)
		(pad "CT10" smd circle
			(at -30.100016 8.168132 270)
			(size 0.4318 0.4318)
			(layers "F.Cu" "F.Mask" "F.Paste")
			(net "GND")
		)
		(pad "CT12" smd circle
			(at -28.472384 8.168132 270)
			(size 0.4318 0.4318)
			(layers "F.Cu" "F.Mask" "F.Paste")
			(net "GND")
		)
		(pad "CT14" smd circle
			(at -26.844498 8.168132 270)
			(size 0.4318 0.4318)
			(layers "F.Cu" "F.Mask" "F.Paste")
			(net "P5E_CPU1_PE2_TX_DP<0>")
		)
		(pad "CT16" smd circle
			(at -25.216612 8.168132 270)
			(size 0.4318 0.4318)
			(layers "F.Cu" "F.Mask" "F.Paste")
			(net "GND")
		)
		(pad "CT18" smd circle
			(at -23.58898 8.168132 270)
			(size 0.4318 0.4318)
			(layers "F.Cu" "F.Mask" "F.Paste")
			(net "I3C_SPD_DDREFGH_CPU1_SDA")
		)
		(pad "CT20" smd circle
			(at -21.961094 8.168132 270)
			(size 0.4318 0.4318)
			(layers "F.Cu" "F.Mask" "F.Paste")
			(net "PD_CPU1_TXT_PLTEN")
		)
		(pad "CT22" smd circle
			(at -20.333462 8.168132 270)
			(size 0.4318 0.4318)
			(layers "F.Cu" "F.Mask" "F.Paste")
			(net "TP_JTAG_CPU1_PLD_TDI")
		)
		(pad "CT24" smd circle
			(at -18.705576 8.168132 270)
			(size 0.4318 0.4318)
			(layers "F.Cu" "F.Mask" "F.Paste")
			(net "NC_FM_IBL_ADR_TRIGGER_CPU1_R")
		)
		(pad "CT26" smd circle
			(at -17.07769 8.168132 270)
			(size 0.4318 0.4318)
			(layers "F.Cu" "F.Mask" "F.Paste")
			(net "NC_CPU1_VIEWPIN_GNR0")
		)
		(pad "CT61" smd circle
			(at 13.008356 8.278114 270)
			(size 0.4318 0.4318)
			(layers "F.Cu" "F.Mask" "F.Paste")
			(net "PU_CPU1_SOCKET_ID2")
		)
		(pad "CT63" smd circle
			(at 14.635988 8.278114 270)
			(size 0.4318 0.4318)
			(layers "F.Cu" "F.Mask" "F.Paste")
			(net "PVCCINFAON_CPU1")
		)
		(pad "CT65" smd circle
			(at 16.263874 8.278114 270)
			(size 0.4318 0.4318)
			(layers "F.Cu" "F.Mask" "F.Paste")
			(net "PVCCINFAON_CPU1")
		)
		(pad "CT67" smd circle
			(at 17.89176 8.278114 270)
			(size 0.4318 0.4318)
			(layers "F.Cu" "F.Mask" "F.Paste")
			(net "PVCCINFAON_CPU1")
		)
		(pad "CT69" smd circle
			(at 19.519392 8.278114 270)
			(size 0.4318 0.4318)
			(layers "F.Cu" "F.Mask" "F.Paste")
			(net "GND")
		)
		(pad "CT71" smd circle
			(at 21.147278 8.278114 270)
			(size 0.4318 0.4318)
			(layers "F.Cu" "F.Mask" "F.Paste")
			(net "PD_PIROM_CPU1_ADDR1")
		)
		(pad "CT73" smd circle
			(at 22.77491 8.278114 270)
			(size 0.4318 0.4318)
			(layers "F.Cu" "F.Mask" "F.Paste")
			(net "GND")
		)
		(pad "CT75" smd circle
			(at 24.402796 8.278114 270)
			(size 0.4318 0.4318)
			(layers "F.Cu" "F.Mask" "F.Paste")
			(net "Net_743")
		)
		(pad "CT77" smd circle
			(at 26.030682 8.278114 270)
			(size 0.4318 0.4318)
			(layers "F.Cu" "F.Mask" "F.Paste")
			(net "PVCCFA_EHV_FIVRA_CPU1")
		)
		(pad "CT79" smd circle
			(at 27.658314 8.278114 270)
			(size 0.4318 0.4318)
			(layers "F.Cu" "F.Mask" "F.Paste")
			(net "GND")
		)
		(pad "CT81" smd circle
			(at 29.2862 8.278114 270)
			(size 0.4318 0.4318)
			(layers "F.Cu" "F.Mask" "F.Paste")
			(net "GND")
		)
		(pad "CT83" smd circle
			(at 30.914086 8.278114 270)
			(size 0.4318 0.4318)
			(layers "F.Cu" "F.Mask" "F.Paste")
			(net "GND")
		)
		(pad "CT85" smd circle
			(at 32.541718 8.278114 270)
			(size 0.4318 0.4318)
			(layers "F.Cu" "F.Mask" "F.Paste")
			(net "PVCCFA_EHV_FIVRA_CPU1")
		)
		(pad "CT87" smd circle
			(at 34.169604 8.278114 270)
			(size 0.4318 0.4318)
			(layers "F.Cu" "F.Mask" "F.Paste")
			(net "P5E_CPU1_PE3_TX_DN<14>")
		)
		(pad "CT89" smd circle
			(at 35.797236 8.278114 270)
			(size 0.4318 0.4318)
			(layers "F.Cu" "F.Mask" "F.Paste")
			(net "GND")
		)
		(pad "CT91" smd oval
			(at 37.425122 8.278114)
			(size 0.381 0.4826)
			(drill
				(offset 0 -0.0508)
			)
			(layers "F.Cu" "F.Mask" "F.Paste")
			(net "P5E_CPU1_PE3_RX_DP<15>")
		)
		(pad "CU1" smd oval
			(at -37.425122 8.638286 180)
			(size 0.381 0.4826)
			(drill
				(offset 0 -0.0508)
			)
			(layers "F.Cu" "F.Mask" "F.Paste")
			(net "UPI_CPU0_CPU1_P0P1_DP<15>")
		)
		(pad "CU3" smd circle
			(at -35.797236 8.638286 270)
			(size 0.4318 0.4318)
			(layers "F.Cu" "F.Mask" "F.Paste")
			(net "PVCCINFAON_CPU1")
		)
		(pad "CU5" smd circle
			(at -34.169604 8.638286 270)
			(size 0.4318 0.4318)
			(layers "F.Cu" "F.Mask" "F.Paste")
			(net "UPI_CPU1_CPU0_P1P0_DN<14>")
		)
		(pad "CU7" smd circle
			(at -32.541718 8.638286 270)
			(size 0.4318 0.4318)
			(layers "F.Cu" "F.Mask" "F.Paste")
			(net "PVCCINFAON_CPU1")
		)
		(pad "CU9" smd circle
			(at -30.914086 8.638286 270)
			(size 0.4318 0.4318)
			(layers "F.Cu" "F.Mask" "F.Paste")
			(net "P5E_CPU1_PE2_RX_DN<0>")
		)
		(pad "CU11" smd circle
			(at -29.2862 8.638286 270)
			(size 0.4318 0.4318)
			(layers "F.Cu" "F.Mask" "F.Paste")
			(net "PVCCINFAON_CPU1")
		)
		(pad "CU13" smd circle
			(at -27.658314 8.638286 270)
			(size 0.4318 0.4318)
			(layers "F.Cu" "F.Mask" "F.Paste")
			(net "P5E_CPU1_PE2_TX_DN<0>")
		)
		(pad "CU15" smd circle
			(at -26.030682 8.638286 270)
			(size 0.4318 0.4318)
			(layers "F.Cu" "F.Mask" "F.Paste")
			(net "PVCCINFAON_CPU1")
		)
		(pad "CU17" smd circle
			(at -24.402796 8.638286 270)
			(size 0.4318 0.4318)
			(layers "F.Cu" "F.Mask" "F.Paste")
			(net "I3C_SPD_DDREFGH_CPU1_SCL")
		)
		(pad "CU19" smd circle
			(at -22.77491 8.638286 270)
			(size 0.4318 0.4318)
			(layers "F.Cu" "F.Mask" "F.Paste")
			(net "GND")
		)
		(pad "CU21" smd circle
			(at -21.147278 8.638286 270)
			(size 0.4318 0.4318)
			(layers "F.Cu" "F.Mask" "F.Paste")
			(net "GND")
		)
		(pad "CU23" smd circle
			(at -19.519392 8.638286 270)
			(size 0.4318 0.4318)
			(layers "F.Cu" "F.Mask" "F.Paste")
			(net "GND")
		)
		(pad "CU25" smd circle
			(at -17.89176 8.638286 270)
			(size 0.4318 0.4318)
			(layers "F.Cu" "F.Mask" "F.Paste")
			(net "GND")
		)
		(pad "CU60" smd circle
			(at 12.19454 8.748268 270)
			(size 0.4318 0.4318)
			(layers "F.Cu" "F.Mask" "F.Paste")
			(net "GND")
		)
		(pad "CU62" smd circle
			(at 13.822426 8.748268 270)
			(size 0.4318 0.4318)
			(layers "F.Cu" "F.Mask" "F.Paste")
			(net "NC_CPU1_LGSSPARE2")
		)
		(pad "CU64" smd circle
			(at 15.450058 8.748268 270)
			(size 0.4318 0.4318)
			(layers "F.Cu" "F.Mask" "F.Paste")
			(net "PVCCINFAON_CPU1")
		)
		(pad "CU66" smd circle
			(at 17.07769 8.748268 270)
			(size 0.4318 0.4318)
			(layers "F.Cu" "F.Mask" "F.Paste")
			(net "GND")
		)
		(pad "CU68" smd circle
			(at 18.705576 8.748268 270)
			(size 0.4318 0.4318)
			(layers "F.Cu" "F.Mask" "F.Paste")
			(net "GND")
		)
		(pad "CU70" smd circle
			(at 20.333462 8.748268 270)
			(size 0.4318 0.4318)
			(layers "F.Cu" "F.Mask" "F.Paste")
			(net "SMB_S3M_CPU1_PIROM_3V3AUX_SCL_1")
		)
		(pad "CU72" smd circle
			(at 21.961094 8.748268 270)
			(size 0.4318 0.4318)
			(layers "F.Cu" "F.Mask" "F.Paste")
			(net "GND")
		)
		(pad "CU74" smd circle
			(at 23.58898 8.748268 270)
			(size 0.4318 0.4318)
			(layers "F.Cu" "F.Mask" "F.Paste")
			(net "Net_718")
		)
		(pad "CU76" smd circle
			(at 25.216612 8.748268 270)
			(size 0.4318 0.4318)
			(layers "F.Cu" "F.Mask" "F.Paste")
			(net "Net_744")
		)
		(pad "CU78" smd circle
			(at 26.844498 8.748268 270)
			(size 0.4318 0.4318)
			(layers "F.Cu" "F.Mask" "F.Paste")
			(net "GND")
		)
		(pad "CU80" smd circle
			(at 28.472384 8.748268 270)
			(size 0.4318 0.4318)
			(layers "F.Cu" "F.Mask" "F.Paste")
			(net "GND")
		)
		(pad "CU82" smd circle
			(at 30.100016 8.748268 270)
			(size 0.4318 0.4318)
			(layers "F.Cu" "F.Mask" "F.Paste")
			(net "GND")
		)
		(pad "CU84" smd circle
			(at 31.727902 8.748268 270)
			(size 0.4318 0.4318)
			(layers "F.Cu" "F.Mask" "F.Paste")
			(net "GND")
		)
		(pad "CU86" smd circle
			(at 33.355534 8.748268 270)
			(size 0.4318 0.4318)
			(layers "F.Cu" "F.Mask" "F.Paste")
			(net "P5E_CPU1_PE3_TX_DP<14>")
		)
		(pad "CU88" smd circle
			(at 34.98342 8.748268 270)
			(size 0.4318 0.4318)
			(layers "F.Cu" "F.Mask" "F.Paste")
			(net "GND")
		)
		(pad "CU90" smd circle
			(at 36.611306 8.748268 270)
			(size 0.4318 0.4318)
			(layers "F.Cu" "F.Mask" "F.Paste")
			(net "P5E_CPU1_PE3_RX_DN<15>")
		)
		(pad "CV2" smd circle
			(at -36.611306 9.107932 270)
			(size 0.4318 0.4318)
			(layers "F.Cu" "F.Mask" "F.Paste")
			(net "UPI_CPU0_CPU1_P0P1_DN<15>")
		)
		(pad "CV4" smd circle
			(at -34.98342 9.107932 270)
			(size 0.4318 0.4318)
			(layers "F.Cu" "F.Mask" "F.Paste")
			(net "GND")
		)
		(pad "CV6" smd circle
			(at -33.355534 9.107932 270)
			(size 0.4318 0.4318)
			(layers "F.Cu" "F.Mask" "F.Paste")
			(net "UPI_CPU1_CPU0_P1P0_DP<14>")
		)
		(pad "CV8" smd circle
			(at -31.727902 9.107932 270)
			(size 0.4318 0.4318)
			(layers "F.Cu" "F.Mask" "F.Paste")
			(net "GND")
		)
		(pad "CV10" smd circle
			(at -30.100016 9.107932 270)
			(size 0.4318 0.4318)
			(layers "F.Cu" "F.Mask" "F.Paste")
			(net "P5E_CPU1_PE2_RX_DP<0>")
		)
		(pad "CV12" smd circle
			(at -28.472384 9.107932 270)
			(size 0.4318 0.4318)
			(layers "F.Cu" "F.Mask" "F.Paste")
			(net "GND")
		)
		(pad "CV14" smd circle
			(at -26.844498 9.107932 270)
			(size 0.4318 0.4318)
			(layers "F.Cu" "F.Mask" "F.Paste")
			(net "P5E_CPU1_PE2_TX_DN<1>")
		)
		(pad "CV16" smd circle
			(at -25.216612 9.107932 270)
			(size 0.4318 0.4318)
			(layers "F.Cu" "F.Mask" "F.Paste")
			(net "GND")
		)
		(pad "CV18" smd circle
			(at -23.58898 9.107932 270)
			(size 0.4318 0.4318)
			(layers "F.Cu" "F.Mask" "F.Paste")
			(net "TP_H_SBLINK5_CPU1_PMDOWN")
		)
		(pad "CV20" smd circle
			(at -21.961094 9.107932 270)
			(size 0.4318 0.4318)
			(layers "F.Cu" "F.Mask" "F.Paste")
			(net "PWRGD_PLT_AUX_CPU1_LVT3")
		)
		(pad "CV22" smd circle
			(at -20.333462 9.107932 270)
			(size 0.4318 0.4318)
			(layers "F.Cu" "F.Mask" "F.Paste")
			(net "TP_JTAG_CPU1_PLD_TMS")
		)
		(pad "CV24" smd circle
			(at -18.705576 9.107932 270)
			(size 0.4318 0.4318)
			(layers "F.Cu" "F.Mask" "F.Paste")
			(net "CPU1_RSVD<135>")
		)
		(pad "CV26" smd circle
			(at -17.07769 9.107932 270)
			(size 0.4318 0.4318)
			(layers "F.Cu" "F.Mask" "F.Paste")
			(net "GND")
		)
		(pad "CV61" smd circle
			(at 13.008356 9.217914 270)
			(size 0.4318 0.4318)
			(layers "F.Cu" "F.Mask" "F.Paste")
			(net "PVCCINFAON_CPU1")
		)
		(pad "CV63" smd circle
			(at 14.635988 9.217914 270)
			(size 0.4318 0.4318)
			(layers "F.Cu" "F.Mask" "F.Paste")
			(net "PVCCINFAON_CPU1")
		)
		(pad "CV65" smd circle
			(at 16.263874 9.217914 270)
			(size 0.4318 0.4318)
			(layers "F.Cu" "F.Mask" "F.Paste")
			(net "PVCCINFAON_CPU1")
		)
		(pad "CV67" smd circle
			(at 17.89176 9.217914 270)
			(size 0.4318 0.4318)
			(layers "F.Cu" "F.Mask" "F.Paste")
			(net "PVCCINFAON_CPU1")
		)
		(pad "CV69" smd circle
			(at 19.519392 9.217914 270)
			(size 0.4318 0.4318)
			(layers "F.Cu" "F.Mask" "F.Paste")
			(net "NC_UART_IBL_CPU1_TXD")
		)
		(pad "CV71" smd circle
			(at 21.147278 9.217914 270)
			(size 0.4318 0.4318)
			(layers "F.Cu" "F.Mask" "F.Paste")
			(net "NC_UART_IBL_CPU1_CTS")
		)
		(pad "CV73" smd circle
			(at 22.77491 9.217914 270)
			(size 0.4318 0.4318)
			(layers "F.Cu" "F.Mask" "F.Paste")
			(net "Net_734")
		)
		(pad "CV75" smd circle
			(at 24.402796 9.217914 270)
			(size 0.4318 0.4318)
			(layers "F.Cu" "F.Mask" "F.Paste")
			(net "GND")
		)
		(pad "CV77" smd circle
			(at 26.030682 9.217914 270)
			(size 0.4318 0.4318)
			(layers "F.Cu" "F.Mask" "F.Paste")
			(net "Net_720")
		)
		(pad "CV79" smd circle
			(at 27.658314 9.217914 270)
			(size 0.4318 0.4318)
			(layers "F.Cu" "F.Mask" "F.Paste")
			(net "GND")
		)
		(pad "CV81" smd circle
			(at 29.2862 9.217914 270)
			(size 0.4318 0.4318)
			(layers "F.Cu" "F.Mask" "F.Paste")
			(net "GND")
		)
		(pad "CV83" smd circle
			(at 30.914086 9.217914 270)
			(size 0.4318 0.4318)
			(layers "F.Cu" "F.Mask" "F.Paste")
			(net "GND")
		)
	)
)
